# BASEBOARD_FAB2 (Tioga Pass) — schematic netlist excerpt (pin names and nets, part order shuffled) for the footprints in the layout excerpt that follows; sources: Cadence DE-HDL packaged netlist, KiCad conversion of Wiwynn_Tioga_Pass_MB.brd

C7A16  CAP  1.0UF 16V 10% X6S  pkg 0402  page 219 : A = VR_PVDDQ_DEF_PH1_VCIN ; B = GND

T1D20  TEST-PAD-12P-1-GP-U  pkg DISCRET-GB1  page 258
  DP  = L10_85OHM_10INCH_DN
  DN  = L10_85OHM_10INCH_DP
  GND(0)  = GND
  GND(1)  = GND
  GND(2)  = GND
  GND(3)  = GND
  GND(4)  = GND
  GND(5)  = GND
  GND(6)  = GND
  GND(7)  = GND
  GND(8)  = GND
  GND(9)  = GND

(kicad_pcb
	(version 20260206)
	(generator "pcbnew")
	(generator_version "10.0")
	(general
		(thickness 1.6)
		(legacy_teardrops no)
	)
	(paper "A4")
	(title_block
		(title "Wiwynn_Tioga_Pass_MB.brd")
		(comment 1 "Tioga Pass / footprints 676-677 of 4770")
	)
	(layers
		(0 "F.Cu" signal "TOP")
		(4 "In1.Cu" signal "L2GND")
		(6 "In2.Cu" signal "L3")
		(8 "In3.Cu" signal "L4GND")
		(10 "In4.Cu" signal "L5")
		(12 "In5.Cu" signal "L6GND")
		(14 "In6.Cu" signal "L7VCC")
		(16 "In7.Cu" signal "L8VCC")
		(18 "In8.Cu" signal "L9GND")
		(20 "In9.Cu" signal "L10")
		(22 "In10.Cu" signal "L11GND")
		(24 "In11.Cu" signal "L12")
		(26 "In12.Cu" signal "L13GND")
		(2 "B.Cu" signal "BOTTOM")
		(9 "F.Adhes" user "F.Adhesive")
		(11 "B.Adhes" user "B.Adhesive")
		(13 "F.Paste" user "Package Geometry/Pastemask Top")
		(15 "B.Paste" user "Package Geometry/Pastemask Bottom")
		(5 "F.SilkS" user "Ref Des/Silkscreen Top")
		(7 "B.SilkS" user "Ref Des/Silkscreen Bottom")
		(1 "F.Mask" user "Board Geometry/Soldermask Top")
		(3 "B.Mask" user "Board Geometry/Soldermask Bottom")
		(17 "Dwgs.User" user "User.Drawings")
		(19 "Cmts.User" user "User.Comments")
		(21 "Eco1.User" user "User.Eco1")
		(23 "Eco2.User" user "User.Eco2")
		(25 "Edge.Cuts" user "Board Geometry/Outline")
		(27 "Margin" user)
		(31 "F.CrtYd" user "Package Geometry/Place Bound Top")
		(29 "B.CrtYd" user "Package Geometry/Place Bound Bottom")
		(35 "F.Fab" user "Ref Des/Assembly Top")
		(33 "B.Fab" user "Ref Des/Assembly Bottom")
	)
	(footprint ""
		(layer "F.Cu")
		(at 349.1738 -157.2768 90)
		(property "Reference" "C7A16"
			(at 0 0 90)
			(layer "F.SilkS")
			(hide yes)
			(effects
				(font
					(size 1.27 1.27)
				)
			)
		)
		(property "Value" ""
			(at 0 0 90)
			(layer "F.Fab")
			(effects
				(font
					(size 1.27 1.27)
				)
			)
		)
		(duplicate_pad_numbers_are_jumpers no)
		(fp_poly
			(pts
				(xy 0.3048 -0.1016) (xy 0.3048 0.9906) (xy -0.3048 0.9906) (xy -0.3048 -0.1016)
			)
			(stroke
				(width 0)
				(type default)
			)
			(fill no)
			(layer "F.CrtYd")
		)
		(fp_line
			(start 0.3048 -0.1016)
			(end -0.3048 -0.1016)
			(stroke
				(width 0.1)
				(type default)
			)
			(layer "F.Fab")
		)
		(fp_line
			(start -0.3048 -0.1016)
			(end -0.3048 0.9906)
			(stroke
				(width 0.1)
				(type default)
			)
			(layer "F.Fab")
		)
		(fp_line
			(start 0.3048 0.9906)
			(end 0.3048 -0.1016)
			(stroke
				(width 0.1)
				(type default)
			)
			(layer "F.Fab")
		)
		(fp_line
			(start -0.3048 0.9906)
			(end 0.3048 0.9906)
			(stroke
				(width 0.1)
				(type default)
			)
			(layer "F.Fab")
		)
		(pad "1" smd rect
			(at 0 0 90)
			(size 0.508 0.508)
			(layers "F.Cu" "F.Mask" "F.Paste")
			(net "VR_PVDDQ_DEF_PH1_VCIN")
		)
		(pad "2" smd rect
			(at 0 0.889 90)
			(size 0.508 0.508)
			(layers "F.Cu" "F.Mask" "F.Paste")
			(net "GND")
		)
		(zone
			(layer "F.Cu")
			(hatch none 0.5)
			(connect_pads
				(clearance 0)
			)
			(min_thickness 0.25)
			(keepout
				(tracks allowed)
				(vias not_allowed)
				(pads allowed)
				(copperpour not_allowed)
				(footprints allowed)
			)
			(placement
				(enabled no)
				(sheetname "")
			)
			(fill
				(thermal_gap 0.5)
				(thermal_bridge_width 0.5)
				(island_removal_mode 0)
			)
			(polygon
				(pts
					(xy 349.4278 -157.0228) (xy 349.4278 -157.5308) (xy 349.8088 -157.5308) (xy 349.8088 -157.0228)
				)
			)
		)
		(zone
			(layer "F.Cu")
			(hatch none 0.5)
			(connect_pads
				(clearance 0)
			)
			(min_thickness 0.25)
			(keepout
				(tracks not_allowed)
				(vias allowed)
				(pads allowed)
				(copperpour not_allowed)
				(footprints allowed)
			)
			(placement
				(enabled no)
				(sheetname "")
			)
			(fill
				(thermal_gap 0.5)
				(thermal_bridge_width 0.5)
				(island_removal_mode 0)
			)
			(polygon
				(pts
					(xy 349.8088 -157.0228) (xy 349.8088 -157.5308) (xy 349.4278 -157.5308) (xy 349.4278 -157.0228)
				)
			)
		)
	)
	(footprint ""
		(layer "F.Cu")
		(at 388.502906 -164.916612 90)
		(property "Reference" "T1D20"
			(at 0 0 90)
			(layer "F.SilkS")
			(hide yes)
			(effects
				(font
					(size 1.27 1.27)
				)
			)
		)
		(property "Value" "*"
			(at -3.4036 -4.46405 90)
			(unlocked yes)
			(layer "F.Fab")
			(hide yes)
			(effects
				(font
					(size 0.889 0.889)
					(thickness 0.1524)
				)
			)
		)
		(property "Device Type" "TEST-PAD-12P-1-GP-U_DISCRET-GBA"
			(at -3.4036 -5.98805 90)
			(unlocked yes)
			(layer "F.Fab")
			(hide yes)
			(effects
				(font
					(size 0.889 0.889)
					(thickness 0.1524)
				)
			)
		)
		(duplicate_pad_numbers_are_jumpers no)
		(fp_line
			(start 2.3622 -4.826)
			(end 2.3622 3.4798)
			(stroke
				(width 0.1524)
				(type default)
			)
			(layer "F.SilkS")
		)
		(fp_line
			(start -2.3876 -4.826)
			(end 2.3622 -4.826)
			(stroke
				(width 0.1524)
				(type default)
			)
			(layer "F.SilkS")
		)
		(fp_line
			(start 2.3622 3.4798)
			(end -2.3876 3.4798)
			(stroke
				(width 0.1524)
				(type default)
			)
			(layer "F.SilkS")
		)
		(fp_line
			(start -2.3876 3.4798)
			(end -2.3876 -4.826)
			(stroke
				(width 0.1524)
				(type default)
			)
			(layer "F.SilkS")
		)
		(fp_rect
			(start -2.6416 3.7338)
			(end 2.6162 -5.08)
			(stroke
				(width 0)
				(type default)
			)
			(fill no)
			(layer "F.CrtYd")
		)
		(fp_rect
			(start -2.6416 3.7338)
			(end 2.6162 -5.08)
			(stroke
				(width 0)
				(type default)
			)
			(fill no)
			(layer "F.Fab")
		)
		(pad "1" smd circle
			(at 0.496824 -1.301496 90)
			(size 0.6604 0.6604)
			(layers "F.Cu" "F.Mask" "F.Paste")
			(net "L10_85OHM_10INCH_DN")
		)
		(pad "2" smd circle
			(at -0.503936 -1.301496 90)
			(size 0.6604 0.6604)
			(layers "F.Cu" "F.Mask" "F.Paste")
			(net "L10_85OHM_10INCH_DP")
		)
		(pad "3" smd custom
			(at -0.00889 0.370078 90)
			(size 0.74295 0.74295)
			(layers "F.Cu" "F.Mask" "F.Paste")
			(net "GND")
			(options
				(clearance outline)
				(anchor circle)
			)
			(primitives
				(gr_poly
					(pts
						(xy -2.1209 1.4859) (xy 2.1209 1.4859) (xy 2.1209 -1.4859) (xy 1.08585 -1.4859) (xy 1.08585 -0.4699)
						(xy -1.08585 -0.4699) (xy -1.08585 -1.4859) (xy -2.1209 -1.4859)
					)
					(width 0)
					(fill yes)
				)
			)
		)
		(pad "4" thru_hole circle
			(at 1.266444 -3.851656 90)
			(size 1.4478 1.4478)
			(drill 1.0414)
			(layers "*.Cu" "*.Mask")
			(remove_unused_layers no)
			(net "GND")
			(clearance 0.1524)
			(thermal_gap 0.1524)
		)
		(pad "5" thru_hole circle
			(at -1.273556 -3.851656 90)
			(size 1.4478 1.4478)
			(drill 1.0414)
			(layers "*.Cu" "*.Mask")
			(remove_unused_layers no)
			(net "GND")
			(clearance 0.1524)
			(thermal_gap 0.1524)
		)
		(pad "6" thru_hole circle
			(at 1.266444 2.498344 90)
			(size 1.4478 1.4478)
			(drill 1.0414)
			(layers "*.Cu" "*.Mask")
			(remove_unused_layers no)
			(net "GND")
			(clearance 0.1524)
			(thermal_gap 0.1524)
		)
		(pad "7" thru_hole circle
			(at -1.273556 2.498344 90)
			(size 1.4478 1.4478)
			(drill 1.0414)
			(layers "*.Cu" "*.Mask")
			(remove_unused_layers no)
			(net "GND")
			(clearance 0.1524)
			(thermal_gap 0.1524)
		)
		(pad "8" thru_hole circle
			(at 1.27 -0.4572 90)
			(size 0.7112 0.7112)
			(drill 0.4064)
			(layers "*.Cu" "*.Mask")
			(remove_unused_layers no)
			(net "GND")
			(clearance 0.1016)
			(thermal_gap 0.1016)
		)
		(pad "9" thru_hole circle
			(at 1.27 0.762 90)
			(size 0.7112 0.7112)
			(drill 0.4064)
			(layers "*.Cu" "*.Mask")
			(remove_unused_layers no)
			(net "GND")
			(clearance 0.1016)
			(thermal_gap 0.1016)
		)
		(pad "10" thru_hole circle
			(at -0.0254 0.762 90)
			(size 0.7112 0.7112)
			(drill 0.4064)
			(layers "*.Cu" "*.Mask")
			(remove_unused_layers no)
			(net "GND")
			(clearance 0.1016)
			(thermal_gap 0.1016)
		)
		(pad "11" thru_hole circle
			(at -1.27 0.762 90)
			(size 0.7112 0.7112)
			(drill 0.4064)
			(layers "*.Cu" "*.Mask")
			(remove_unused_layers no)
			(net "GND")
			(clearance 0.1016)
			(thermal_gap 0.1016)
		)
		(pad "12" thru_hole circle
			(at -1.27 -0.4572 90)
			(size 0.7112 0.7112)
			(drill 0.4064)
			(layers "*.Cu" "*.Mask")
			(remove_unused_layers no)
			(net "GND")
			(clearance 0.1016)
			(thermal_gap 0.1016)
		)
	)
)
